(kicad_pcb
	(version 20260206)
	(generator "pcbnew")
	(generator_version "10.0")
	(general
		(thickness 1.6)
		(legacy_teardrops no)
	)
	(paper "A4")
	(title_block
		(title "panther-plus-userver — 13130-1b_20150205.brd")
		(comment 1 "Honey Badger (Wiwynn) / footprint 1 of 1509 (GF1), pads 111-164 of 164")
	)
	(layers
		(0 "F.Cu" signal "TOP")
		(4 "In1.Cu" signal "L2")
		(6 "In2.Cu" signal "L3")
		(8 "In3.Cu" signal "L4")
		(10 "In4.Cu" signal "L5")
		(12 "In5.Cu" signal "L6")
		(14 "In6.Cu" signal "L7")
		(16 "In7.Cu" signal "L8")
		(18 "In8.Cu" signal "L9")
		(20 "In9.Cu" signal "L10")
		(22 "In10.Cu" signal "L11")
		(2 "B.Cu" signal "BOTTOM")
		(9 "F.Adhes" user "F.Adhesive")
		(11 "B.Adhes" user "B.Adhesive")
		(13 "F.Paste" user "Package Geometry/Pastemask Top")
		(15 "B.Paste" user "Package Geometry/Pastemask Bottom")
		(5 "F.SilkS" user "Ref Des/Silkscreen Top")
		(7 "B.SilkS" user "Ref Des/Silkscreen Bottom")
		(1 "F.Mask" user "Board Geometry/Soldermask Top")
		(3 "B.Mask" user "Board Geometry/Soldermask Bottom")
		(17 "Dwgs.User" user "User.Drawings")
		(19 "Cmts.User" user "User.Comments")
		(21 "Eco1.User" user "User.Eco1")
		(23 "Eco2.User" user "User.Eco2")
		(25 "Edge.Cuts" user "Board Geometry/Outline")
		(27 "Margin" user)
		(31 "F.CrtYd" user "Package Geometry/Place Bound Top")
		(29 "B.CrtYd" user "Package Geometry/Place Bound Bottom")
		(35 "F.Fab" user "Ref Des/Assembly Top")
		(33 "B.Fab" user "Ref Des/Assembly Bottom")
	)
	(footprint ""
		(layer "F.Cu")
		(at 86.849966 -4.100068)
		(property "Reference" "GF1"
			(at 0 0 0)
			(layer "F.SilkS")
			(hide yes)
			(effects
				(font
					(size 1.27 1.27)
				)
			)
		)
		(property "Value" "GF-PCIE-164P-15-GP"
			(at 15.2654 -6.2992 0)
			(unlocked yes)
			(layer "F.Fab")
			(hide yes)
			(effects
				(font
					(size 1.016 1.016)
					(thickness 0.1524)
				)
			)
		)
		(property "Device Type" "GF-PCIE-164P-15"
			(at 15.2654 -7.8232 0)
			(unlocked yes)
			(layer "F.Fab")
			(hide yes)
			(effects
				(font
					(size 1.016 1.016)
					(thickness 0.1524)
				)
			)
		)
		(duplicate_pad_numbers_are_jumpers no)
		(pad "B29" smd rect
			(at -18.50009 -1.7145)
			(size 0.7112 4.191)
			(drill
				(offset 0 -0.381)
			)
			(layers "F.Cu" "F.Mask" "F.Paste")
			(net "GND")
		)
		(pad "B30" smd rect
			(at -19.500088 -1.7145)
			(size 0.7112 4.191)
			(drill
				(offset 0 -0.381)
			)
			(layers "F.Cu" "F.Mask" "F.Paste")
			(net "GND")
		)
		(pad "B31" smd rect
			(at -20.500086 -1.7145)
			(size 0.7112 4.191)
			(drill
				(offset 0 -0.381)
			)
			(layers "F.Cu" "F.Mask" "F.Paste")
			(net "SATA2_TX_C_DP0")
		)
		(pad "B32" smd rect
			(at -21.500084 -1.7145)
			(size 0.7112 4.191)
			(drill
				(offset 0 -0.381)
			)
			(layers "F.Cu" "F.Mask" "F.Paste")
			(net "SATA2_TX_C_DN0")
		)
		(pad "B33" smd rect
			(at -22.500082 -1.7145)
			(size 0.7112 4.191)
			(drill
				(offset 0 -0.381)
			)
			(layers "F.Cu" "F.Mask" "F.Paste")
			(net "GND")
		)
		(pad "B34" smd rect
			(at -23.50008 -1.7145)
			(size 0.7112 4.191)
			(drill
				(offset 0 -0.381)
			)
			(layers "F.Cu" "F.Mask" "F.Paste")
			(net "GND")
		)
		(pad "B35" smd rect
			(at -24.500078 -1.7145)
			(size 0.7112 4.191)
			(drill
				(offset 0 -0.381)
			)
			(layers "F.Cu" "F.Mask" "F.Paste")
			(net "CLK_100M_CLKBUFF_ENET_DP")
		)
		(pad "B36" smd rect
			(at -25.500076 -1.7145)
			(size 0.7112 4.191)
			(drill
				(offset 0 -0.381)
			)
			(layers "F.Cu" "F.Mask" "F.Paste")
			(net "CLK_100M_CLKBUFF_ENET_DN")
		)
		(pad "B37" smd rect
			(at -26.500074 -1.7145)
			(size 0.7112 4.191)
			(drill
				(offset 0 -0.381)
			)
			(layers "F.Cu" "F.Mask" "F.Paste")
			(net "GND")
		)
		(pad "B38" smd rect
			(at -27.500072 -1.7145)
			(size 0.7112 4.191)
			(drill
				(offset 0 -0.381)
			)
			(layers "F.Cu" "F.Mask" "F.Paste")
			(net "GND")
		)
		(pad "B39" smd rect
			(at -28.50007 -1.7145)
			(size 0.7112 4.191)
			(drill
				(offset 0 -0.381)
			)
			(layers "F.Cu" "F.Mask" "F.Paste")
			(net "PCIE1_RESET#")
		)
		(pad "B40" smd rect
			(at -29.500068 -1.7145)
			(size 0.7112 4.191)
			(drill
				(offset 0 -0.381)
			)
			(layers "F.Cu" "F.Mask" "F.Paste")
			(net "PCIE2_RESET#")
		)
		(pad "B41" smd rect
			(at -30.500066 -1.7145)
			(size 0.7112 4.191)
			(drill
				(offset 0 -0.381)
			)
			(layers "F.Cu" "F.Mask" "F.Paste")
			(net "GND")
		)
		(pad "B42" smd rect
			(at -31.500064 -1.7145)
			(size 0.7112 4.191)
			(drill
				(offset 0 -0.381)
			)
			(layers "F.Cu" "F.Mask" "F.Paste")
			(net "GND")
		)
		(pad "B43" smd rect
			(at -32.500062 -1.7145)
			(size 0.7112 4.191)
			(drill
				(offset 0 -0.381)
			)
			(layers "F.Cu" "F.Mask" "F.Paste")
			(net "GBE_R_SMBCLK")
		)
		(pad "B44" smd rect
			(at -33.50006 -1.7145)
			(size 0.7112 4.191)
			(drill
				(offset 0 -0.381)
			)
			(layers "F.Cu" "F.Mask" "F.Paste")
			(net "GBE_R_SMDATA")
		)
		(pad "B45" smd rect
			(at -34.500058 -1.7145)
			(size 0.7112 4.191)
			(drill
				(offset 0 -0.381)
			)
			(layers "F.Cu" "F.Mask" "F.Paste")
			(net "GND")
		)
		(pad "B46" smd rect
			(at -35.500056 -1.7145)
			(size 0.7112 4.191)
			(drill
				(offset 0 -0.381)
			)
			(layers "F.Cu" "F.Mask" "F.Paste")
			(net "GND")
		)
		(pad "B47" smd rect
			(at -36.500054 -1.7145)
			(size 0.7112 4.191)
			(drill
				(offset 0 -0.381)
			)
			(layers "F.Cu" "F.Mask" "F.Paste")
			(net "CPU_GBE_TX_C_DP0")
		)
		(pad "B48" smd rect
			(at -37.500052 -1.7145)
			(size 0.7112 4.191)
			(drill
				(offset 0 -0.381)
			)
			(layers "F.Cu" "F.Mask" "F.Paste")
			(net "CPU_GBE_TX_C_DN0")
		)
		(pad "B49" smd rect
			(at -38.50005 -1.7145)
			(size 0.7112 4.191)
			(drill
				(offset 0 -0.381)
			)
			(layers "F.Cu" "F.Mask" "F.Paste")
			(net "GND")
		)
		(pad "B50" smd rect
			(at -39.500048 -1.7145)
			(size 0.7112 4.191)
			(drill
				(offset 0 -0.381)
			)
			(layers "F.Cu" "F.Mask" "F.Paste")
			(net "GND")
		)
		(pad "B51" smd rect
			(at -40.500046 -1.7145)
			(size 0.7112 4.191)
			(drill
				(offset 0 -0.381)
			)
			(layers "F.Cu" "F.Mask" "F.Paste")
			(net "P2E_CPU_SAS_TX_DP4")
		)
		(pad "B52" smd rect
			(at -41.500044 -1.7145)
			(size 0.7112 4.191)
			(drill
				(offset 0 -0.381)
			)
			(layers "F.Cu" "F.Mask" "F.Paste")
			(net "P2E_CPU_SAS_TX_DN4")
		)
		(pad "B53" smd rect
			(at -42.500042 -1.7145)
			(size 0.7112 4.191)
			(drill
				(offset 0 -0.381)
			)
			(layers "F.Cu" "F.Mask" "F.Paste")
			(net "GND")
		)
		(pad "B54" smd rect
			(at -43.50004 -1.7145)
			(size 0.7112 4.191)
			(drill
				(offset 0 -0.381)
			)
			(layers "F.Cu" "F.Mask" "F.Paste")
			(net "GND")
		)
		(pad "B55" smd rect
			(at -44.500038 -1.7145)
			(size 0.7112 4.191)
			(drill
				(offset 0 -0.381)
			)
			(layers "F.Cu" "F.Mask" "F.Paste")
			(net "P2E_CPU_SAS_TX_DP5")
		)
		(pad "B56" smd rect
			(at -45.500036 -1.7145)
			(size 0.7112 4.191)
			(drill
				(offset 0 -0.381)
			)
			(layers "F.Cu" "F.Mask" "F.Paste")
			(net "P2E_CPU_SAS_TX_DN5")
		)
		(pad "B57" smd rect
			(at -46.500034 -1.7145)
			(size 0.7112 4.191)
			(drill
				(offset 0 -0.381)
			)
			(layers "F.Cu" "F.Mask" "F.Paste")
			(net "GND")
		)
		(pad "B58" smd rect
			(at -47.500032 -1.7145)
			(size 0.7112 4.191)
			(drill
				(offset 0 -0.381)
			)
			(layers "F.Cu" "F.Mask" "F.Paste")
			(net "GND")
		)
		(pad "B59" smd rect
			(at -48.50003 -1.7145)
			(size 0.7112 4.191)
			(drill
				(offset 0 -0.381)
			)
			(layers "F.Cu" "F.Mask" "F.Paste")
			(net "P2E_CPU_SAS_TX_DP6")
		)
		(pad "B60" smd rect
			(at -49.500028 -1.7145)
			(size 0.7112 4.191)
			(drill
				(offset 0 -0.381)
			)
			(layers "F.Cu" "F.Mask" "F.Paste")
			(net "P2E_CPU_SAS_TX_DN6")
		)
		(pad "B61" smd rect
			(at -50.500026 -1.7145)
			(size 0.7112 4.191)
			(drill
				(offset 0 -0.381)
			)
			(layers "F.Cu" "F.Mask" "F.Paste")
			(net "GND")
		)
		(pad "B62" smd rect
			(at -51.500024 -1.7145)
			(size 0.7112 4.191)
			(drill
				(offset 0 -0.381)
			)
			(layers "F.Cu" "F.Mask" "F.Paste")
			(net "GND")
		)
		(pad "B63" smd rect
			(at -52.500022 -1.7145)
			(size 0.7112 4.191)
			(drill
				(offset 0 -0.381)
			)
			(layers "F.Cu" "F.Mask" "F.Paste")
			(net "P2E_CPU_SAS_TX_DP7")
		)
		(pad "B64" smd rect
			(at -53.50002 -1.7145)
			(size 0.7112 4.191)
			(drill
				(offset 0 -0.381)
			)
			(layers "F.Cu" "F.Mask" "F.Paste")
			(net "P2E_CPU_SAS_TX_DN7")
		)
		(pad "B65" smd rect
			(at -54.500018 -1.7145)
			(size 0.7112 4.191)
			(drill
				(offset 0 -0.381)
			)
			(layers "F.Cu" "F.Mask" "F.Paste")
			(net "GND")
		)
		(pad "B66" smd rect
			(at -55.500016 -1.7145)
			(size 0.7112 4.191)
			(drill
				(offset 0 -0.381)
			)
			(layers "F.Cu" "F.Mask" "F.Paste")
			(net "GND")
		)
		(pad "B67" smd rect
			(at -56.500014 -1.7145)
			(size 0.7112 4.191)
			(drill
				(offset 0 -0.381)
			)
			(layers "F.Cu" "F.Mask" "F.Paste")
			(net "P2E_CPU_ETH10G_TX_DP8")
		)
		(pad "B68" smd rect
			(at -57.500012 -1.7145)
			(size 0.7112 4.191)
			(drill
				(offset 0 -0.381)
			)
			(layers "F.Cu" "F.Mask" "F.Paste")
			(net "P2E_CPU_ETH10G_TX_DN8")
		)
		(pad "B69" smd rect
			(at -58.50001 -1.7145)
			(size 0.7112 4.191)
			(drill
				(offset 0 -0.381)
			)
			(layers "F.Cu" "F.Mask" "F.Paste")
			(net "GND")
		)
		(pad "B70" smd rect
			(at -59.500008 -1.7145)
			(size 0.7112 4.191)
			(drill
				(offset 0 -0.381)
			)
			(layers "F.Cu" "F.Mask" "F.Paste")
			(net "GND")
		)
		(pad "B71" smd rect
			(at -60.500006 -1.7145)
			(size 0.7112 4.191)
			(drill
				(offset 0 -0.381)
			)
			(layers "F.Cu" "F.Mask" "F.Paste")
			(net "P2E_CPU_ETH10G_TX_DP9")
		)
		(pad "B72" smd rect
			(at -61.500004 -1.7145)
			(size 0.7112 4.191)
			(drill
				(offset 0 -0.381)
			)
			(layers "F.Cu" "F.Mask" "F.Paste")
			(net "P2E_CPU_ETH10G_TX_DN9")
		)
		(pad "B73" smd rect
			(at -62.500002 -1.7145)
			(size 0.7112 4.191)
			(drill
				(offset 0 -0.381)
			)
			(layers "F.Cu" "F.Mask" "F.Paste")
			(net "GND")
		)
		(pad "B74" smd rect
			(at -63.5 -1.7145)
			(size 0.7112 4.191)
			(drill
				(offset 0 -0.381)
			)
			(layers "F.Cu" "F.Mask" "F.Paste")
			(net "GND")
		)
		(pad "B75" smd rect
			(at -64.499998 -1.7145)
			(size 0.7112 4.191)
			(drill
				(offset 0 -0.381)
			)
			(layers "F.Cu" "F.Mask" "F.Paste")
			(net "P2E_CPU_ETH10G_TX_DP10")
		)
		(pad "B76" smd rect
			(at -65.499996 -1.7145)
			(size 0.7112 4.191)
			(drill
				(offset 0 -0.381)
			)
			(layers "F.Cu" "F.Mask" "F.Paste")
			(net "P2E_CPU_ETH10G_TX_DN10")
		)
		(pad "B77" smd rect
			(at -66.499994 -1.7145)
			(size 0.7112 4.191)
			(drill
				(offset 0 -0.381)
			)
			(layers "F.Cu" "F.Mask" "F.Paste")
			(net "GND")
		)
		(pad "B78" smd rect
			(at -67.499992 -1.7145)
			(size 0.7112 4.191)
			(drill
				(offset 0 -0.381)
			)
			(layers "F.Cu" "F.Mask" "F.Paste")
			(net "GND")
		)
		(pad "B79" smd rect
			(at -68.49999 -1.7145)
			(size 0.7112 4.191)
			(drill
				(offset 0 -0.381)
			)
			(layers "F.Cu" "F.Mask" "F.Paste")
			(net "P2E_CPU_ETH10G_TX_DP11")
		)
		(pad "B80" smd rect
			(at -69.499988 -1.7145)
			(size 0.7112 4.191)
			(drill
				(offset 0 -0.381)
			)
			(layers "F.Cu" "F.Mask" "F.Paste")
			(net "P2E_CPU_ETH10G_TX_DN11")
		)
		(pad "B81" smd rect
			(at -70.499986 -2.5908)
			(size 0.7112 3.2004)
			(layers "F.Cu" "F.Mask" "F.Paste")
			(net "GND")
		)
		(pad "B82" smd rect
			(at -71.499984 -1.7145)
			(size 0.7112 4.191)
			(drill
				(offset 0 -0.381)
			)
			(layers "F.Cu" "F.Mask" "F.Paste")
			(net "GND")
		)
	)
)
